# S9S_MB_2U (Grand Teton) — schematic netlist excerpt (pin names and nets, part order shuffled) for the footprints in the layout excerpt that follows; sources: Cadence DE-HDL packaged netlist, KiCad conversion of 03242023_DA0F0TMBIJ0_F0T_Motherboard_J_brd_V01_OCP.brd

R4537  Q_RES  0 5% CHIP  pkg 0402LF  page 166 : A = FM_P2E_EN_N ; B = CLK_GEN2_GPU_FPGA_OE_OR_N
R1347  Q_RES  1K 1% CHIP  pkg 0402LF  page 239 : A = PD_GTL2014_BMC_JTAG_VREF_1 ; B = GND

(kicad_pcb
	(version 20260206)
	(generator "pcbnew")
	(generator_version "10.0")
	(general
		(thickness 1.6)
		(legacy_teardrops no)
	)
	(paper "A4")
	(title_block
		(title "03242023_DA0F0TMBIJ0_F0T_Motherboard_J_brd_V01_OCP.brd")
		(comment 1 "Grand Teton / footprints 2519-2520 of 6105")
	)
	(layers
		(0 "F.Cu" signal "TOP")
		(4 "In1.Cu" signal "GND")
		(6 "In2.Cu" signal "IN1")
		(8 "In3.Cu" signal "GND1")
		(10 "In4.Cu" signal "IN2")
		(12 "In5.Cu" signal "GND2")
		(14 "In6.Cu" signal "IN3")
		(16 "In7.Cu" signal "GND3")
		(18 "In8.Cu" signal "VCC")
		(20 "In9.Cu" signal "VCC1")
		(22 "In10.Cu" signal "GND4")
		(24 "In11.Cu" signal "IN4")
		(26 "In12.Cu" signal "GND5")
		(28 "In13.Cu" signal "IN5")
		(30 "In14.Cu" signal "GND6")
		(32 "In15.Cu" signal "IN6")
		(34 "In16.Cu" signal "GND7")
		(2 "B.Cu" signal "BOTTOM")
		(9 "F.Adhes" user "F.Adhesive")
		(11 "B.Adhes" user "B.Adhesive")
		(13 "F.Paste" user "Package Geometry/Pastemask Top")
		(15 "B.Paste" user "Package Geometry/Pastemask Bottom")
		(5 "F.SilkS" user "Ref Des/Silkscreen Top")
		(7 "B.SilkS" user "Ref Des/Silkscreen Bottom")
		(1 "F.Mask" user "Board Geometry/Soldermask Top")
		(3 "B.Mask" user "Board Geometry/Soldermask Bottom")
		(17 "Dwgs.User" user "User.Drawings")
		(19 "Cmts.User" user "User.Comments")
		(21 "Eco1.User" user "User.Eco1")
		(23 "Eco2.User" user "User.Eco2")
		(25 "Edge.Cuts" user "Board Geometry/Outline")
		(27 "Margin" user)
		(31 "F.CrtYd" user "Package Geometry/Place Bound Top")
		(29 "B.CrtYd" user "Package Geometry/Place Bound Bottom")
		(35 "F.Fab" user "Ref Des/Assembly Top")
		(33 "B.Fab" user "Ref Des/Assembly Bottom")
	)
	(footprint ""
		(layer "F.Cu")
		(at 27.22118 -385.760468 90)
		(property "Reference" "R4537"
			(at 0 0 90)
			(layer "F.SilkS")
			(hide yes)
			(effects
				(font
					(size 1.27 1.27)
				)
			)
		)
		(property "Value" ""
			(at 0 0 90)
			(layer "F.Fab")
			(effects
				(font
					(size 1.27 1.27)
				)
			)
		)
		(duplicate_pad_numbers_are_jumpers no)
		(fp_line
			(start 0.7874 -0.4064)
			(end 0.7874 0.4064)
			(stroke
				(width 0.1524)
				(type default)
			)
			(layer "F.SilkS")
		)
		(fp_line
			(start -0.7874 -0.4064)
			(end 0.7874 -0.4064)
			(stroke
				(width 0.1524)
				(type default)
			)
			(layer "F.SilkS")
		)
		(fp_line
			(start 0.7874 0.4064)
			(end -0.7874 0.4064)
			(stroke
				(width 0.1524)
				(type default)
			)
			(layer "F.SilkS")
		)
		(fp_line
			(start -0.7874 0.4064)
			(end -0.7874 -0.4064)
			(stroke
				(width 0.1524)
				(type default)
			)
			(layer "F.SilkS")
		)
		(fp_line
			(start -0.12065 -0.305054)
			(end -0.12065 -0.2794)
			(stroke
				(width 0.1)
				(type default)
			)
			(layer "F.Fab")
		)
		(fp_line
			(start -0.67945 -0.305054)
			(end -0.12065 -0.305054)
			(stroke
				(width 0.1)
				(type default)
			)
			(layer "F.Fab")
		)
		(fp_line
			(start 0.67945 -0.3048)
			(end 0.67945 0.3048)
			(stroke
				(width 0.1)
				(type default)
			)
			(layer "F.Fab")
		)
		(fp_line
			(start 0.12065 -0.3048)
			(end 0.67945 -0.3048)
			(stroke
				(width 0.1)
				(type default)
			)
			(layer "F.Fab")
		)
		(fp_line
			(start 0.12065 -0.2794)
			(end 0.12065 -0.3048)
			(stroke
				(width 0.1)
				(type default)
			)
			(layer "F.Fab")
		)
		(fp_line
			(start -0.12065 -0.2794)
			(end 0.12065 -0.2794)
			(stroke
				(width 0.1)
				(type default)
			)
			(layer "F.Fab")
		)
		(fp_line
			(start 0.120396 0.2794)
			(end -0.12065 0.2794)
			(stroke
				(width 0.1)
				(type default)
			)
			(layer "F.Fab")
		)
		(fp_line
			(start -0.12065 0.2794)
			(end -0.12065 0.3048)
			(stroke
				(width 0.1)
				(type default)
			)
			(layer "F.Fab")
		)
		(fp_line
			(start 0.67945 0.3048)
			(end 0.120396 0.3048)
			(stroke
				(width 0.1)
				(type default)
			)
			(layer "F.Fab")
		)
		(fp_line
			(start 0.120396 0.3048)
			(end 0.120396 0.2794)
			(stroke
				(width 0.1)
				(type default)
			)
			(layer "F.Fab")
		)
		(fp_line
			(start -0.12065 0.3048)
			(end -0.67945 0.3048)
			(stroke
				(width 0.1)
				(type default)
			)
			(layer "F.Fab")
		)
		(fp_line
			(start -0.67945 0.3048)
			(end -0.67945 -0.305054)
			(stroke
				(width 0.1)
				(type default)
			)
			(layer "F.Fab")
		)
		(pad "1" smd circle
			(at -0.40005 0 90)
			(size 0 0)
			(layers "F.Cu" "F.Mask" "F.Paste")
			(net "FM_P2E_EN_N")
		)
		(pad "2" smd circle
			(at 0.40005 0 90)
			(size 0 0)
			(layers "F.Cu" "F.Mask" "F.Paste")
			(net "CLK_GEN2_GPU_FPGA_OE_OR_N")
		)
	)
	(footprint ""
		(layer "F.Cu")
		(at 371.545358 -92.962984 -90)
		(property "Reference" "R1347"
			(at 0 0 270)
			(layer "F.SilkS")
			(hide yes)
			(effects
				(font
					(size 1.27 1.27)
				)
			)
		)
		(property "Value" ""
			(at 0 0 270)
			(layer "F.Fab")
			(effects
				(font
					(size 1.27 1.27)
				)
			)
		)
		(duplicate_pad_numbers_are_jumpers no)
		(fp_line
			(start -0.7874 0.4064)
			(end -0.7874 -0.4064)
			(stroke
				(width 0.1524)
				(type default)
			)
			(layer "F.SilkS")
		)
		(fp_line
			(start 0.7874 0.4064)
			(end -0.7874 0.4064)
			(stroke
				(width 0.1524)
				(type default)
			)
			(layer "F.SilkS")
		)
		(fp_line
			(start -0.7874 -0.4064)
			(end 0.7874 -0.4064)
			(stroke
				(width 0.1524)
				(type default)
			)
			(layer "F.SilkS")
		)
		(fp_line
			(start 0.7874 -0.4064)
			(end 0.7874 0.4064)
			(stroke
				(width 0.1524)
				(type default)
			)
			(layer "F.SilkS")
		)
		(fp_line
			(start -0.67945 0.3048)
			(end -0.67945 -0.305054)
			(stroke
				(width 0.1)
				(type default)
			)
			(layer "F.Fab")
		)
		(fp_line
			(start -0.12065 0.3048)
			(end -0.67945 0.3048)
			(stroke
				(width 0.1)
				(type default)
			)
			(layer "F.Fab")
		)
		(fp_line
			(start 0.120396 0.3048)
			(end 0.120396 0.2794)
			(stroke
				(width 0.1)
				(type default)
			)
			(layer "F.Fab")
		)
		(fp_line
			(start 0.67945 0.3048)
			(end 0.120396 0.3048)
			(stroke
				(width 0.1)
				(type default)
			)
			(layer "F.Fab")
		)
		(fp_line
			(start -0.12065 0.2794)
			(end -0.12065 0.3048)
			(stroke
				(width 0.1)
				(type default)
			)
			(layer "F.Fab")
		)
		(fp_line
			(start 0.120396 0.2794)
			(end -0.12065 0.2794)
			(stroke
				(width 0.1)
				(type default)
			)
			(layer "F.Fab")
		)
		(fp_line
			(start -0.12065 -0.2794)
			(end 0.12065 -0.2794)
			(stroke
				(width 0.1)
				(type default)
			)
			(layer "F.Fab")
		)
		(fp_line
			(start 0.12065 -0.2794)
			(end 0.12065 -0.3048)
			(stroke
				(width 0.1)
				(type default)
			)
			(layer "F.Fab")
		)
		(fp_line
			(start 0.12065 -0.3048)
			(end 0.67945 -0.3048)
			(stroke
				(width 0.1)
				(type default)
			)
			(layer "F.Fab")
		)
		(fp_line
			(start 0.67945 -0.3048)
			(end 0.67945 0.3048)
			(stroke
				(width 0.1)
				(type default)
			)
			(layer "F.Fab")
		)
		(fp_line
			(start -0.67945 -0.305054)
			(end -0.12065 -0.305054)
			(stroke
				(width 0.1)
				(type default)
			)
			(layer "F.Fab")
		)
		(fp_line
			(start -0.12065 -0.305054)
			(end -0.12065 -0.2794)
			(stroke
				(width 0.1)
				(type default)
			)
			(layer "F.Fab")
		)
		(pad "1" smd circle
			(at -0.40005 0 270)
			(size 0 0)
			(layers "F.Cu" "F.Mask" "F.Paste")
			(net "PD_GTL2014_BMC_JTAG_VREF_1")
		)
		(pad "2" smd circle
			(at 0.40005 0 270)
			(size 0 0)
			(layers "F.Cu" "F.Mask" "F.Paste")
			(net "GND")
		)
	)
)
